# S9S_MB_2U (Grand Teton) — schematic netlist excerpt (pin names and nets, part order shuffled) for the footprints in the layout excerpt that follows; sources: Cadence DE-HDL packaged netlist, KiCad conversion of 03242023_DA0F0TMBIJ0_F0T_Motherboard_J_brd_V01_OCP.brd

J35  SCONN168_ME1016810202011  IO  pkg CON_F168S2H7D_P0-6W2-95_LUH  page 159
  GND_A1  = GND
  GND_A2  = GND
  GND_A3  = GND
  GND_A4  = GND
  GND_A5  = GND
  GND_A6  = GND
  SMCLK  = SMB_OCP_V3_2_3V3AUX_BUF_R_SCL
  SMDAT  = SMB_OCP_V3_2_3V3AUX_BUF_R_SDA
  \smrst#\  = RST_SMB_OCP_V3_2_N
  \prsnta#\  = OCP_V3_1_PRSNTA_R_N
  \perst1#\  = RST_PERST1_OCP_V3_2_N
  \prsntb2#\  = OCP_V3_2_PRSNT2_R_N
  GND_A13  = GND
  REFCLKN1  = CLK_100M_OCP_V3_2_B_DN
  REFCLKP1  = CLK_100M_OCP_V3_2_B_DP
  GND_A16  = GND
  PERN0  = P5E_CPU1_PE1_RX_DN<0>
  PERP0  = P5E_CPU1_PE1_RX_DP<0>
  GND_A19  = GND
  PERN1  = P5E_CPU1_PE1_RX_DN<1>
  PERP1  = P5E_CPU1_PE1_RX_DP<1>
  GND_A22  = GND
  PERN2  = P5E_CPU1_PE1_RX_DN<2>
  PERP2  = P5E_CPU1_PE1_RX_DP<2>
  GND_A25  = GND
  PERN3  = P5E_CPU1_PE1_RX_DN<3>
  PERP3  = P5E_CPU1_PE1_RX_DP<3>
  GND_A28  = GND
  GND_A29  = GND
  PERN4  = P5E_CPU1_PE1_RX_DN<4>
  PERP4  = P5E_CPU1_PE1_RX_DP<4>
  GND_A32  = GND
  PERN5  = P5E_CPU1_PE1_RX_DN<5>
  PERP5  = P5E_CPU1_PE1_RX_DP<5>
  GND_A35  = GND
  PERN6  = P5E_CPU1_PE1_RX_DN<6>
  PERP6  = P5E_CPU1_PE1_RX_DP<6>
  GND_A38  = GND
  PERN7  = P5E_CPU1_PE1_RX_DN<7>
  PERP7  = P5E_CPU1_PE1_RX_DP<7>
  GND_A41  = GND
  \prsntb1#\  = OCP_V3_2_PRSNT1_R_N
  GND_A43  = GND
  PERN8  = P5E_CPU1_PE1_RX_DN<8>
  PERP8  = P5E_CPU1_PE1_RX_DP<8>
  GND_A46  = GND
  PERN9  = P5E_CPU1_PE1_RX_DN<9>
  PERP9  = P5E_CPU1_PE1_RX_DP<9>
  GND_A49  = GND
  PERN10  = P5E_CPU1_PE1_RX_DN<10>
  PERP10  = P5E_CPU1_PE1_RX_DP<10>
  GND_A52  = GND
  PERN11  = P5E_CPU1_PE1_RX_DN<11>
  PERP11  = P5E_CPU1_PE1_RX_DP<11>
  GND_A55  = GND
  PERN12  = P5E_CPU1_PE1_RX_DN<12>
  PERP12  = P5E_CPU1_PE1_RX_DP<12>
  GND_A58  = GND
  PERN13  = P5E_CPU1_PE1_RX_DN<13>
  PERP13  = P5E_CPU1_PE1_RX_DP<13>
  GND_A61  = GND
  PERN14  = P5E_CPU1_PE1_RX_DN<14>
  PERP14  = P5E_CPU1_PE1_RX_DP<14>
  GND_A64  = GND
  PERN15  = P5E_CPU1_PE1_RX_DN<15>
  PERP15  = P5E_CPU1_PE1_RX_DP<15>
  GND_A67  = GND
  USB_DATN  = USB2_5_R1_DN
  USB_DATP  = USB2_5_R1_DP
  \pwrbrk0#\  = OCP_V3_2_PWRBRK_N
  \+12v_edge_b1\  = P12V_OCP_V3_2
  \+12v_edge_b2\  = P12V_OCP_V3_2
  \+12v_edge_b3\  = P12V_OCP_V3_2
  \+12v_edge_b4\  = P12V_OCP_V3_2
  \+12v_edge_b5\  = P12V_OCP_V3_2
  \+12v_edge_b6\  = P12V_OCP_V3_2
  \bif0#\  = OCP_V3_2_BIF0_R_N
  \bif1#\  = OCP_V3_2_BIF1_R_N
  \bif2#\  = OCP_V3_2_BIF2_R_N
  \perst0#\  = RST_PERST0_OCP_V3_2_N
  \+3.3v_edge\  = P3V3_OCP_V3_2
  AUX_PWR_EN  = OCP_V3_2_AUX_PWR_EN_R
  GND_B13  = GND
  REFCLKN0  = CLK_100M_OCP_V3_2_A_DN
  REFCLKP0  = CLK_100M_OCP_V3_2_A_DP
  GND_B16  = GND
  PETN0  = P5E_CPU1_PE1_TX_C_DP<0>
  PETP0  = P5E_CPU1_PE1_TX_C_DN<0>
  GND_B19  = GND
  PETN1  = P5E_CPU1_PE1_TX_C_DN<1>
  PETP1  = P5E_CPU1_PE1_TX_C_DP<1>
  GND_B22  = GND
  PETN2  = P5E_CPU1_PE1_TX_C_DP<2>
  PETP2  = P5E_CPU1_PE1_TX_C_DN<2>
  GND_B25  = GND
  PETN3  = P5E_CPU1_PE1_TX_C_DN<3>
  PETP3  = P5E_CPU1_PE1_TX_C_DP<3>
  GND_B28  = GND
  GND_B29  = GND
  PETN4  = P5E_CPU1_PE1_TX_C_DP<4>
  PETP4  = P5E_CPU1_PE1_TX_C_DN<4>
  GND_B32  = GND
  PETN5  = P5E_CPU1_PE1_TX_C_DN<5>
  PETP5  = P5E_CPU1_PE1_TX_C_DP<5>
  GND_B35  = GND
  PETN6  = P5E_CPU1_PE1_TX_C_DP<6>
  PETP6  = P5E_CPU1_PE1_TX_C_DN<6>
  GND_B38  = GND
  PETN7  = P5E_CPU1_PE1_TX_C_DN<7>
  PETP7  = P5E_CPU1_PE1_TX_C_DP<7>
  GND_B41  = GND
  \prsntb0#\  = OCP_V3_2_PRSNT0_R_N
  GND_B43  = GND
  PETN8  = P5E_CPU1_PE1_TX_C_DP<8>
  PETP8  = P5E_CPU1_PE1_TX_C_DN<8>
  GND_B46  = GND
  PETN9  = P5E_CPU1_PE1_TX_C_DN<9>
  PETP9  = P5E_CPU1_PE1_TX_C_DP<9>
  GND_B49  = GND
  PETN10  = P5E_CPU1_PE1_TX_C_DP<10>
  PETP10  = P5E_CPU1_PE1_TX_C_DN<10>
  GND_B52  = GND
  PETN11  = P5E_CPU1_PE1_TX_C_DN<11>
  PETP11  = P5E_CPU1_PE1_TX_C_DP<11>
  GND_B55  = GND
  PETN12  = P5E_CPU1_PE1_TX_C_DP<12>
  PETP12  = P5E_CPU1_PE1_TX_C_DN<12>
  GND_B58  = GND
  PETN13  = P5E_CPU1_PE1_TX_C_DN<13>
  PETP13  = P5E_CPU1_PE1_TX_C_DP<13>
  GND_B61  = GND
  PETN14  = P5E_CPU1_PE1_TX_C_DP<14>
  PETP14  = P5E_CPU1_PE1_TX_C_DN<14>
  GND_B64  = GND
  PETN15  = P5E_CPU1_PE1_TX_C_DN<15>
  PETP15  = P5E_CPU1_PE1_TX_C_DP<15>
  GND_B67  = GND
  RFU1_NC_B68  = TP_OCP_V3_2_B68
  RFU1_NC_B69  = TP_OCP_V3_2_B69
  \prsntb3#\  = OCP_V3_2_PRSNT3_R_N
  G1  = GND
  G2  = GND
  G3  = GND
  G4  = GND
  G5  = GND
  \perst2#\  = RST_PERST2_OCP_V3_2_N
  \perst3#\  = RST_PERST3_OCP_V3_2_N
  \wake#\  = IRQ_LVC3_OCP_V3_2_WAKE_N
  RBT_ARB_IN  = OCP_V3_2_ISO1_RBT_ARB_IN
  RBT_ARB_OUT  = OCP_V3_2_ISO2_RBT_ARB_OUT
  SLOT_ID1  = OCP_V3_2_ID1
  RBT_TX_EN  = NCSI_OCP_V3_2_TX_EN
  RBT_TXD1  = NCSI_OCP_V3_2_TXD1
  RBT_TXD0  = NCSI_OCP_V3_2_TXD0
  GND_OA10  = GND
  REFCLKN3  = CLK_100M_OCP_V3_2_D_DN
  REFCLKP3  = CLK_100M_OCP_V3_2_D_DP
  GND_OA13  = GND
  RBT_CLK_IN  = CLK_50M_NCSI_OCP_V3_2_ISO
  NIC_PWR_GOOD  = FM_OCP_V3_2_PWR_GOOD
  MAIN_PWR_EN  = OCP_V3_2_MAIN_PWR_EN_R
  \ld#\  = SGPIO_OCP_V3_2_LD_N
  DATA_IN  = SGPIO_OCP_V3_2_DATAIN
  DATA_OUT  = SGPIO_OCP_V3_2_DATAOUT
  CLK  = SGPIO_OCP_V3_2_CLK
  SLOT_ID0  = OCP_V3_2_ID0
  RBT_RXD1  = NCSI_OCP_V3_2_RXD1
  RBT_RXD0  = NCSI_OCP_V3_2_RXD0
  GND_OB10  = GND
  REFCLKN2  = CLK_100M_OCP_V3_2_C_DN
  REFCLKP2  = CLK_100M_OCP_V3_2_C_DP
  GND_OB13  = GND
  RBT_CRS_DV  = NCSI_OCP_V3_2_CRS_DV

(kicad_pcb
	(version 20260206)
	(generator "pcbnew")
	(generator_version "10.0")
	(general
		(thickness 1.6)
		(legacy_teardrops no)
	)
	(paper "A4")
	(title_block
		(title "03242023_DA0F0TMBIJ0_F0T_Motherboard_J_brd_V01_OCP.brd")
		(comment 1 "Grand Teton / footprint 3456 of 6105 (J35), pads 133-174 of 175")
	)
	(layers
		(0 "F.Cu" signal "TOP")
		(4 "In1.Cu" signal "GND")
		(6 "In2.Cu" signal "IN1")
		(8 "In3.Cu" signal "GND1")
		(10 "In4.Cu" signal "IN2")
		(12 "In5.Cu" signal "GND2")
		(14 "In6.Cu" signal "IN3")
		(16 "In7.Cu" signal "GND3")
		(18 "In8.Cu" signal "VCC")
		(20 "In9.Cu" signal "VCC1")
		(22 "In10.Cu" signal "GND4")
		(24 "In11.Cu" signal "IN4")
		(26 "In12.Cu" signal "GND5")
		(28 "In13.Cu" signal "IN5")
		(30 "In14.Cu" signal "GND6")
		(32 "In15.Cu" signal "IN6")
		(34 "In16.Cu" signal "GND7")
		(2 "B.Cu" signal "BOTTOM")
		(9 "F.Adhes" user "F.Adhesive")
		(11 "B.Adhes" user "B.Adhesive")
		(13 "F.Paste" user "Package Geometry/Pastemask Top")
		(15 "B.Paste" user "Package Geometry/Pastemask Bottom")
		(5 "F.SilkS" user "Ref Des/Silkscreen Top")
		(7 "B.SilkS" user "Ref Des/Silkscreen Bottom")
		(1 "F.Mask" user "Board Geometry/Soldermask Top")
		(3 "B.Mask" user "Board Geometry/Soldermask Bottom")
		(17 "Dwgs.User" user "User.Drawings")
		(19 "Cmts.User" user "User.Comments")
		(21 "Eco1.User" user "User.Eco1")
		(23 "Eco2.User" user "User.Eco2")
		(25 "Edge.Cuts" user "Board Geometry/Outline")
		(27 "Margin" user)
		(31 "F.CrtYd" user "Package Geometry/Place Bound Top")
		(29 "B.CrtYd" user "Package Geometry/Place Bound Bottom")
		(35 "F.Fab" user "Ref Des/Assembly Top")
		(33 "B.Fab" user "Ref Des/Assembly Bottom")
	)
	(footprint ""
		(layer "F.Cu")
		(at 47.401988 -5.569966 -90)
		(property "Reference" "J35"
			(at -16.848074 29.242004 0)
			(unlocked yes)
			(layer "F.SilkS")
			(effects
				(font
					(size 0.7874 0.5842)
					(thickness 0.1524)
				)
				(justify left)
			)
		)
		(property "Value" ""
			(at 0 0 270)
			(layer "F.Fab")
			(effects
				(font
					(size 1.27 1.27)
				)
			)
		)
		(duplicate_pad_numbers_are_jumpers no)
		(pad "B61" smd rect
			(at -5.700014 25.254966 180)
			(size 0.381 1.4478)
			(layers "F.Cu" "F.Mask" "F.Paste")
			(net "GND")
		)
		(pad "B62" smd rect
			(at -5.700014 25.854914 180)
			(size 0.381 1.4478)
			(layers "F.Cu" "F.Mask" "F.Paste")
			(net "P5E_CPU1_PE1_TX_C_DP<14>")
		)
		(pad "B63" smd rect
			(at -5.700014 26.455116 180)
			(size 0.381 1.4478)
			(layers "F.Cu" "F.Mask" "F.Paste")
			(net "P5E_CPU1_PE1_TX_C_DN<14>")
		)
		(pad "B64" smd rect
			(at -5.700014 27.055064 180)
			(size 0.381 1.4478)
			(layers "F.Cu" "F.Mask" "F.Paste")
			(net "GND")
		)
		(pad "B65" smd rect
			(at -5.700014 27.655012 180)
			(size 0.381 1.4478)
			(layers "F.Cu" "F.Mask" "F.Paste")
			(net "P5E_CPU1_PE1_TX_C_DN<15>")
		)
		(pad "B66" smd rect
			(at -5.700014 28.25496 180)
			(size 0.381 1.4478)
			(layers "F.Cu" "F.Mask" "F.Paste")
			(net "P5E_CPU1_PE1_TX_C_DP<15>")
		)
		(pad "B67" smd rect
			(at -5.700014 28.854908 180)
			(size 0.381 1.4478)
			(layers "F.Cu" "F.Mask" "F.Paste")
			(net "GND")
		)
		(pad "B68" smd rect
			(at -5.700014 29.45511 180)
			(size 0.381 1.4478)
			(layers "F.Cu" "F.Mask" "F.Paste")
			(net "TP_OCP_V3_2_B68")
		)
		(pad "B69" smd rect
			(at -5.700014 30.055058 180)
			(size 0.381 1.4478)
			(layers "F.Cu" "F.Mask" "F.Paste")
			(net "TP_OCP_V3_2_B69")
		)
		(pad "B70" smd rect
			(at -5.700014 30.655006 180)
			(size 0.381 1.4478)
			(layers "F.Cu" "F.Mask" "F.Paste")
			(net "OCP_V3_2_PRSNT3_R_N")
		)
		(pad "G1" thru_hole circle
			(at 2.400046 -32.759904 180)
			(size 1.6256 1.6256)
			(drill 1.1176)
			(layers "*.Cu" "*.Mask")
			(remove_unused_layers no)
			(net "GND")
			(clearance 0)
		)
		(pad "G2" thru_hole circle
			(at 2.400046 -20.379944 180)
			(size 1.6256 1.6256)
			(drill 1.1176)
			(layers "*.Cu" "*.Mask")
			(remove_unused_layers no)
			(net "GND")
			(clearance 0)
		)
		(pad "G3" thru_hole circle
			(at 2.400046 0 180)
			(size 1.6256 1.6256)
			(drill 1.1176)
			(layers "*.Cu" "*.Mask")
			(remove_unused_layers no)
			(net "GND")
			(clearance 0)
		)
		(pad "G4" thru_hole circle
			(at 2.400046 12.5349 180)
			(size 1.6256 1.6256)
			(drill 1.1176)
			(layers "*.Cu" "*.Mask")
			(remove_unused_layers no)
			(net "GND")
			(clearance 0)
		)
		(pad "G5" thru_hole circle
			(at 2.400046 32.759904 180)
			(size 1.6256 1.6256)
			(drill 1.1176)
			(layers "*.Cu" "*.Mask")
			(remove_unused_layers no)
			(net "GND")
			(clearance 0)
		)
		(pad "OA1" smd rect
			(at -2.750058 -30.660086 180)
			(size 0.381 1.4478)
			(layers "F.Cu" "F.Mask" "F.Paste")
			(net "RST_PERST2_OCP_V3_2_N")
		)
		(pad "OA2" smd rect
			(at -2.750058 -30.059884 180)
			(size 0.381 1.4478)
			(layers "F.Cu" "F.Mask" "F.Paste")
			(net "RST_PERST3_OCP_V3_2_N")
		)
		(pad "OA3" smd rect
			(at -2.750058 -29.459936 180)
			(size 0.381 1.4478)
			(layers "F.Cu" "F.Mask" "F.Paste")
			(net "IRQ_LVC3_OCP_V3_2_WAKE_N")
		)
		(pad "OA4" smd rect
			(at -2.750058 -28.859988 180)
			(size 0.381 1.4478)
			(layers "F.Cu" "F.Mask" "F.Paste")
			(net "OCP_V3_2_ISO1_RBT_ARB_IN")
		)
		(pad "OA5" smd rect
			(at -2.750058 -28.26004 180)
			(size 0.381 1.4478)
			(layers "F.Cu" "F.Mask" "F.Paste")
			(net "OCP_V3_2_ISO2_RBT_ARB_OUT")
		)
		(pad "OA6" smd rect
			(at -2.750058 -27.660092 180)
			(size 0.381 1.4478)
			(layers "F.Cu" "F.Mask" "F.Paste")
			(net "OCP_V3_2_ID1")
		)
		(pad "OA7" smd rect
			(at -2.750058 -27.05989 180)
			(size 0.381 1.4478)
			(layers "F.Cu" "F.Mask" "F.Paste")
			(net "NCSI_OCP_V3_2_TX_EN")
		)
		(pad "OA8" smd rect
			(at -2.750058 -26.459942 180)
			(size 0.381 1.4478)
			(layers "F.Cu" "F.Mask" "F.Paste")
			(net "NCSI_OCP_V3_2_TXD1")
		)
		(pad "OA9" smd rect
			(at -2.750058 -25.859994 180)
			(size 0.381 1.4478)
			(layers "F.Cu" "F.Mask" "F.Paste")
			(net "NCSI_OCP_V3_2_TXD0")
		)
		(pad "OA10" smd rect
			(at -2.750058 -25.260046 180)
			(size 0.381 1.4478)
			(layers "F.Cu" "F.Mask" "F.Paste")
			(net "GND")
		)
		(pad "OA11" smd rect
			(at -2.750058 -24.660098 180)
			(size 0.381 1.4478)
			(layers "F.Cu" "F.Mask" "F.Paste")
			(net "CLK_100M_OCP_V3_2_D_DN")
		)
		(pad "OA12" smd rect
			(at -2.750058 -24.059896 180)
			(size 0.381 1.4478)
			(layers "F.Cu" "F.Mask" "F.Paste")
			(net "CLK_100M_OCP_V3_2_D_DP")
		)
		(pad "OA13" smd rect
			(at -2.750058 -23.459948 180)
			(size 0.381 1.4478)
			(layers "F.Cu" "F.Mask" "F.Paste")
			(net "GND")
		)
		(pad "OA14" smd rect
			(at -2.750058 -22.86 180)
			(size 0.381 1.4478)
			(layers "F.Cu" "F.Mask" "F.Paste")
			(net "CLK_50M_NCSI_OCP_V3_2_ISO")
		)
		(pad "OB1" smd rect
			(at -5.700014 -30.660086 180)
			(size 0.381 1.4478)
			(layers "F.Cu" "F.Mask" "F.Paste")
			(net "FM_OCP_V3_2_PWR_GOOD")
		)
		(pad "OB2" smd rect
			(at -5.700014 -30.059884 180)
			(size 0.381 1.4478)
			(layers "F.Cu" "F.Mask" "F.Paste")
			(net "OCP_V3_2_MAIN_PWR_EN_R")
		)
		(pad "OB3" smd rect
			(at -5.700014 -29.459936 180)
			(size 0.381 1.4478)
			(layers "F.Cu" "F.Mask" "F.Paste")
			(net "SGPIO_OCP_V3_2_LD_N")
		)
		(pad "OB4" smd rect
			(at -5.700014 -28.859988 180)
			(size 0.381 1.4478)
			(layers "F.Cu" "F.Mask" "F.Paste")
			(net "SGPIO_OCP_V3_2_DATAIN")
		)
		(pad "OB5" smd rect
			(at -5.700014 -28.26004 180)
			(size 0.381 1.4478)
			(layers "F.Cu" "F.Mask" "F.Paste")
			(net "SGPIO_OCP_V3_2_DATAOUT")
		)
		(pad "OB6" smd rect
			(at -5.700014 -27.660092 180)
			(size 0.381 1.4478)
			(layers "F.Cu" "F.Mask" "F.Paste")
			(net "SGPIO_OCP_V3_2_CLK")
		)
		(pad "OB7" smd rect
			(at -5.700014 -27.05989 180)
			(size 0.381 1.4478)
			(layers "F.Cu" "F.Mask" "F.Paste")
			(net "OCP_V3_2_ID0")
		)
		(pad "OB8" smd rect
			(at -5.700014 -26.459942 180)
			(size 0.381 1.4478)
			(layers "F.Cu" "F.Mask" "F.Paste")
			(net "NCSI_OCP_V3_2_RXD1")
		)
		(pad "OB9" smd rect
			(at -5.700014 -25.859994 180)
			(size 0.381 1.4478)
			(layers "F.Cu" "F.Mask" "F.Paste")
			(net "NCSI_OCP_V3_2_RXD0")
		)
		(pad "OB10" smd rect
			(at -5.700014 -25.260046 180)
			(size 0.381 1.4478)
			(layers "F.Cu" "F.Mask" "F.Paste")
			(net "GND")
		)
		(pad "OB11" smd rect
			(at -5.700014 -24.660098 180)
			(size 0.381 1.4478)
			(layers "F.Cu" "F.Mask" "F.Paste")
			(net "CLK_100M_OCP_V3_2_C_DN")
		)
		(pad "OB12" smd rect
			(at -5.700014 -24.059896 180)
			(size 0.381 1.4478)
			(layers "F.Cu" "F.Mask" "F.Paste")
			(net "CLK_100M_OCP_V3_2_C_DP")
		)
		(pad "OB13" smd rect
			(at -5.700014 -23.459948 180)
			(size 0.381 1.4478)
			(layers "F.Cu" "F.Mask" "F.Paste")
			(net "GND")
		)
	)
)
